# T6G (Grand Teton) — schematic netlist excerpt (pin names and nets, part order shuffled) for the footprints in the layout excerpt that follows; sources: Cadence DE-HDL packaged netlist, KiCad conversion of 04192023_DAF0TMB3IC0_F0TG_MB_C_brd_V02_OCP.brd

PU50  ISL99390FRZTR5935  ISL99390FRZ-TR5935 IC  pkg QFN21_6X5XB  page 198
  VOS  = PVDDCR_SOC_P0_VOS2
  AGND  = GND
  VCC  = PVDDCR_SOC_P0_VCC2
  PVCC  = PVDDCR_CPU0_P0_PVCC
  PGND1  = GND
  GL1  = NC_PVDDCR_SOC_P0_GL1_2
  PGND2  = GND
  SW  = SW_PVDDCR_SOC_P0_SW2
  VIN1  = SW_P12V_AUX_PVDDCR_SOC_P0_FLT
  VIN2  = SW_P12V_AUX_PVDDCR_SOC_P0_FLT
  DNC  = NC_PVDDCR_SOC_P0_DNC2
  PHASE  = SW_PVDDCR_SOC_P0_PH2
  BOOT  = SW_PVDDCR_SOC_P0_BOOT2
  PWM  = PVDDCR_SOC_P0_PWM2
  EN  = PVDDCR_SOC_P0_VCC2
  TOUT_FLT  = PVDDCR_SOC_P0_TEMP1
  LSET  = PVDDCR_SOC_P0_LSET2
  IOUT  = PVDDCR_SOC_P0_IMON2
  REFIN  = PVDDCR_CPU0_P0_VCCS
  PGND3  = GND
  GL2  = NC_PVDDCR_SOC_P0_GL2_2

(kicad_pcb
	(version 20260206)
	(generator "pcbnew")
	(generator_version "10.0")
	(general
		(thickness 1.6)
		(legacy_teardrops no)
	)
	(paper "A4")
	(title_block
		(title "04192023_DAF0TMB3IC0_F0TG_MB_C_brd_V02_OCP.brd")
		(comment 1 "Grand Teton / footprints 4424-4424 of 8354")
	)
	(layers
		(0 "F.Cu" signal "TOP")
		(4 "In1.Cu" signal "GND")
		(6 "In2.Cu" signal "IN1")
		(8 "In3.Cu" signal "GND1")
		(10 "In4.Cu" signal "IN2")
		(12 "In5.Cu" signal "GND2")
		(14 "In6.Cu" signal "IN3")
		(16 "In7.Cu" signal "GND3")
		(18 "In8.Cu" signal "VCC")
		(20 "In9.Cu" signal "VCC1")
		(22 "In10.Cu" signal "GND4")
		(24 "In11.Cu" signal "IN4")
		(26 "In12.Cu" signal "GND5")
		(28 "In13.Cu" signal "IN5")
		(30 "In14.Cu" signal "GND6")
		(32 "In15.Cu" signal "IN6")
		(34 "In16.Cu" signal "GND7")
		(2 "B.Cu" signal "BOTTOM")
		(9 "F.Adhes" user "F.Adhesive")
		(11 "B.Adhes" user "B.Adhesive")
		(13 "F.Paste" user "Package Geometry/Pastemask Top")
		(15 "B.Paste" user "Package Geometry/Pastemask Bottom")
		(5 "F.SilkS" user "Ref Des/Silkscreen Top")
		(7 "B.SilkS" user "Ref Des/Silkscreen Bottom")
		(1 "F.Mask" user "Board Geometry/Soldermask Top")
		(3 "B.Mask" user "Board Geometry/Soldermask Bottom")
		(17 "Dwgs.User" user "User.Drawings")
		(19 "Cmts.User" user "User.Comments")
		(21 "Eco1.User" user "User.Eco1")
		(23 "Eco2.User" user "User.Eco2")
		(25 "Edge.Cuts" user "Board Geometry/Outline")
		(27 "Margin" user)
		(31 "F.CrtYd" user "Package Geometry/Place Bound Top")
		(29 "B.CrtYd" user "Package Geometry/Place Bound Bottom")
		(35 "F.Fab" user "Ref Des/Assembly Top")
		(33 "B.Fab" user "Ref Des/Assembly Bottom")
	)
	(footprint ""
		(layer "F.Cu")
		(at 406.147778 -168.59377 180)
		(property "Reference" "PU50"
			(at 5.635752 -4.803394 0)
			(unlocked yes)
			(layer "F.SilkS")
			(effects
				(font
					(size 0.7874 0.5842)
					(thickness 0.1524)
				)
				(justify left)
			)
		)
		(property "Value" ""
			(at 0 0 180)
			(layer "F.Fab")
			(effects
				(font
					(size 1.27 1.27)
				)
			)
		)
		(duplicate_pad_numbers_are_jumpers no)
		(fp_line
			(start 2.500122 2.999994)
			(end 2.2987 2.999994)
			(stroke
				(width 0.1524)
				(type default)
			)
			(layer "F.SilkS")
		)
		(fp_line
			(start 2.500122 2.339594)
			(end 2.500122 2.999994)
			(stroke
				(width 0.1524)
				(type default)
			)
			(layer "F.SilkS")
		)
		(fp_line
			(start 2.500122 -2.999994)
			(end 2.500122 -2.44348)
			(stroke
				(width 0.1524)
				(type default)
			)
			(layer "F.SilkS")
		)
		(fp_line
			(start 2.31394 -2.999994)
			(end 2.500122 -2.999994)
			(stroke
				(width 0.1524)
				(type default)
			)
			(layer "F.SilkS")
		)
		(fp_line
			(start -2.2987 2.999994)
			(end -2.500122 2.999994)
			(stroke
				(width 0.1524)
				(type default)
			)
			(layer "F.SilkS")
		)
		(fp_line
			(start -2.500122 2.999994)
			(end -2.500122 2.339594)
			(stroke
				(width 0.1524)
				(type default)
			)
			(layer "F.SilkS")
		)
		(fp_line
			(start -2.500122 0.6604)
			(end -2.500122 0.229108)
			(stroke
				(width 0.1524)
				(type default)
			)
			(layer "F.SilkS")
		)
		(fp_line
			(start -2.500122 -2.529078)
			(end -2.500122 -2.999994)
			(stroke
				(width 0.1524)
				(type default)
			)
			(layer "F.SilkS")
		)
		(fp_line
			(start -2.500122 -2.999994)
			(end -2.24409 -2.999994)
			(stroke
				(width 0.1524)
				(type default)
			)
			(layer "F.SilkS")
		)
		(fp_poly
			(pts
				(xy -2.758948 -2.425192) (xy -3.526028 -2.680716) (xy -3.014472 -3.192272)
			)
			(stroke
				(width 0)
				(type default)
			)
			(fill yes)
			(layer "F.SilkS")
		)
		(fp_line
			(start 2.500122 2.999994)
			(end -2.500122 2.999994)
			(stroke
				(width 0.1)
				(type default)
			)
			(layer "F.Fab")
		)
		(fp_line
			(start 2.500122 -2.999994)
			(end 2.500122 2.999994)
			(stroke
				(width 0.1)
				(type default)
			)
			(layer "F.Fab")
		)
		(fp_line
			(start -2.500122 2.999994)
			(end -2.500122 -2.999994)
			(stroke
				(width 0.1)
				(type default)
			)
			(layer "F.Fab")
		)
		(fp_line
			(start -2.500122 -2.999994)
			(end 2.500122 -2.999994)
			(stroke
				(width 0.1)
				(type default)
			)
			(layer "F.Fab")
		)
		(fp_poly
			(pts
				(xy -4.218432 -2.783078) (xy -4.218432 -1.767078) (xy -3.202432 -2.275078)
			)
			(stroke
				(width 0)
				(type default)
			)
			(fill yes)
			(layer "F.Fab")
		)
		(pad "1" smd rect
			(at -2.400046 -2.275078 270)
			(size 0.2286 0.6096)
			(layers "F.Cu" "F.Mask" "F.Paste")
			(net "PVDDCR_SOC_P0_VOS2")
		)
		(pad "2" smd rect
			(at -2.400046 -1.82499 270)
			(size 0.2286 0.6096)
			(layers "F.Cu" "F.Mask" "F.Paste")
			(net "GND")
		)
		(pad "3" smd rect
			(at -2.400046 -1.374902 270)
			(size 0.2286 0.6096)
			(layers "F.Cu" "F.Mask" "F.Paste")
			(net "PVDDCR_SOC_P0_VCC2")
		)
		(pad "4" smd rect
			(at -2.400046 -0.925068 270)
			(size 0.2286 0.6096)
			(layers "F.Cu" "F.Mask" "F.Paste")
			(net "PVDDCR_CPU0_P0_PVCC")
		)
		(pad "5" smd rect
			(at -2.400046 -0.47498 270)
			(size 0.2286 0.6096)
			(layers "F.Cu" "F.Mask" "F.Paste")
			(net "GND")
		)
		(pad "6" smd rect
			(at -2.400046 -0.024892 270)
			(size 0.2286 0.6096)
			(layers "F.Cu" "F.Mask" "F.Paste")
			(net "NC_PVDDCR_SOC_P0_GL1_2")
		)
		(pad "7_9-20_24" smd circle
			(at 0 1.150112 270)
			(size 0 0)
			(layers "F.Cu" "F.Mask" "F.Paste")
			(net "GND")
		)
		(pad "10_19" smd rect
			(at 0 2.899918 270)
			(size 0.6096 4.318)
			(layers "F.Cu" "F.Mask" "F.Paste")
			(net "SW_PVDDCR_SOC_P0_SW2")
		)
		(pad "25_29" smd rect
			(at 1.549908 -1.279906 90)
			(size 2.0574 2.3114)
			(layers "F.Cu" "F.Mask" "F.Paste")
			(net "SW_P12V_AUX_PVDDCR_SOC_P0_FLT")
		)
		(pad "30" smd rect
			(at 2.05994 -2.899918 180)
			(size 0.2286 0.6096)
			(layers "F.Cu" "F.Mask" "F.Paste")
			(net "SW_P12V_AUX_PVDDCR_SOC_P0_FLT")
		)
		(pad "31" smd rect
			(at 1.610106 -2.899918 180)
			(size 0.2286 0.6096)
			(layers "F.Cu" "F.Mask" "F.Paste")
			(net "NC_PVDDCR_SOC_P0_DNC2")
		)
		(pad "32" smd rect
			(at 1.160018 -2.899918 180)
			(size 0.2286 0.6096)
			(layers "F.Cu" "F.Mask" "F.Paste")
			(net "SW_PVDDCR_SOC_P0_PH2")
		)
		(pad "33" smd rect
			(at 0.70993 -2.899918 180)
			(size 0.2286 0.6096)
			(layers "F.Cu" "F.Mask" "F.Paste")
			(net "SW_PVDDCR_SOC_P0_BOOT2")
		)
		(pad "34" smd rect
			(at 0.260096 -2.899918 180)
			(size 0.2286 0.6096)
			(layers "F.Cu" "F.Mask" "F.Paste")
			(net "PVDDCR_SOC_P0_PWM2")
		)
		(pad "35" smd rect
			(at -0.189992 -2.899918 180)
			(size 0.2286 0.6096)
			(layers "F.Cu" "F.Mask" "F.Paste")
			(net "PVDDCR_SOC_P0_VCC2")
		)
		(pad "36" smd rect
			(at -0.64008 -2.899918 180)
			(size 0.2286 0.6096)
			(layers "F.Cu" "F.Mask" "F.Paste")
			(net "PVDDCR_SOC_P0_TEMP1")
		)
		(pad "37" smd rect
			(at -1.089914 -2.899918 180)
			(size 0.2286 0.6096)
			(layers "F.Cu" "F.Mask" "F.Paste")
			(net "PVDDCR_SOC_P0_LSET2")
		)
		(pad "38" smd rect
			(at -1.540002 -2.899918 180)
			(size 0.2286 0.6096)
			(layers "F.Cu" "F.Mask" "F.Paste")
			(net "PVDDCR_SOC_P0_IMON2")
		)
		(pad "39" smd rect
			(at -1.99009 -2.899918 180)
			(size 0.2286 0.6096)
			(layers "F.Cu" "F.Mask" "F.Paste")
			(net "PVDDCR_CPU0_P0_VCCS")
		)
		(pad "40" smd rect
			(at -0.87503 -1.27508 180)
			(size 1.7526 1.9558)
			(layers "F.Cu" "F.Mask" "F.Paste")
			(net "GND")
		)
		(pad "41" smd rect
			(at -1.525016 0.249936 90)
			(size 0.3048 0.4572)
			(layers "F.Cu" "F.Mask" "F.Paste")
			(net "NC_PVDDCR_SOC_P0_GL2_2")
		)
		(zone
			(layer "F.Cu")
			(hatch none 0.5)
			(connect_pads
				(clearance 0)
			)
			(min_thickness 0.25)
			(keepout
				(tracks not_allowed)
				(vias allowed)
				(pads allowed)
				(copperpour not_allowed)
				(footprints allowed)
			)
			(placement
				(enabled no)
				(sheetname "")
			)
			(fill
				(thermal_gap 0.5)
				(thermal_bridge_width 0.5)
				(island_removal_mode 0)
			)
			(polygon
				(pts
					(xy 408.6479 -171.186856) (xy 408.6479 -170.844464) (xy 403.647656 -170.844464) (xy 403.647656 -171.175934)
					(xy 403.937978 -171.175934) (xy 403.937978 -171.138088) (xy 408.357578 -171.138088) (xy 408.357578 -171.186856)
				)
			)
		)
		(zone
			(layer "F.Cu")
			(hatch none 0.5)
			(connect_pads
				(clearance 0)
			)
			(min_thickness 0.25)
			(keepout
				(tracks not_allowed)
				(vias allowed)
				(pads allowed)
				(copperpour not_allowed)
				(footprints allowed)
			)
			(placement
				(enabled no)
				(sheetname "")
			)
			(fill
				(thermal_gap 0.5)
				(thermal_bridge_width 0.5)
				(island_removal_mode 0)
			)
			(polygon
				(pts
					(xy 406.095708 -168.34739) (xy 406.095708 -166.28999) (xy 407.949908 -166.28999) (xy 407.949908 -166.531036)
					(xy 408.192224 -166.531036) (xy 408.192224 -166.049452) (xy 404.298658 -166.049452) (xy 404.298658 -166.234364)
					(xy 405.80437 -166.234364) (xy 405.80437 -168.393364) (xy 403.647656 -168.393364) (xy 403.647656 -168.643046)
					(xy 405.800052 -168.643046)
				)
			)
		)
	)
)
